# BASEBOARD_FAB2 (Tioga Pass) — schematic netlist excerpt (pin names and nets, part order shuffled) for the footprints in the layout excerpt that follows; sources: Cadence DE-HDL packaged netlist, KiCad conversion of Wiwynn_Tioga_Pass_MB.brd

R1U61  RES  0.0 5% EMPTY  pkg 0402  page 152 : A = H_CPU1_MEMKLM_MEMHOT_LVT3_K_N ; B = H_CPU1_MEMKLM_MEMHOT_G_PCH_N
C5G19  CAP_A  47UF 4V 20% X5R  pkg 0603V  page 217 : A = PVDDQ_ABC ; B = GND
R1U35  RES  150.0 1% CHIP  pkg 0402  page 152 : A = PVCCIO_CPU1 ; B = H_CPU1_MEMKLM_MEMHOT_G_N

(kicad_pcb
	(version 20260206)
	(generator "pcbnew")
	(generator_version "10.0")
	(general
		(thickness 1.6)
		(legacy_teardrops no)
	)
	(paper "A4")
	(title_block
		(title "Wiwynn_Tioga_Pass_MB.brd")
		(comment 1 "Tioga Pass / footprints 670-672 of 4770")
	)
	(layers
		(0 "F.Cu" signal "TOP")
		(4 "In1.Cu" signal "L2GND")
		(6 "In2.Cu" signal "L3")
		(8 "In3.Cu" signal "L4GND")
		(10 "In4.Cu" signal "L5")
		(12 "In5.Cu" signal "L6GND")
		(14 "In6.Cu" signal "L7VCC")
		(16 "In7.Cu" signal "L8VCC")
		(18 "In8.Cu" signal "L9GND")
		(20 "In9.Cu" signal "L10")
		(22 "In10.Cu" signal "L11GND")
		(24 "In11.Cu" signal "L12")
		(26 "In12.Cu" signal "L13GND")
		(2 "B.Cu" signal "BOTTOM")
		(9 "F.Adhes" user "F.Adhesive")
		(11 "B.Adhes" user "B.Adhesive")
		(13 "F.Paste" user "Package Geometry/Pastemask Top")
		(15 "B.Paste" user "Package Geometry/Pastemask Bottom")
		(5 "F.SilkS" user "Ref Des/Silkscreen Top")
		(7 "B.SilkS" user "Ref Des/Silkscreen Bottom")
		(1 "F.Mask" user "Board Geometry/Soldermask Top")
		(3 "B.Mask" user "Board Geometry/Soldermask Bottom")
		(17 "Dwgs.User" user "User.Drawings")
		(19 "Cmts.User" user "User.Comments")
		(21 "Eco1.User" user "User.Eco1")
		(23 "Eco2.User" user "User.Eco2")
		(25 "Edge.Cuts" user "Board Geometry/Outline")
		(27 "Margin" user)
		(31 "F.CrtYd" user "Package Geometry/Place Bound Top")
		(29 "B.CrtYd" user "Package Geometry/Place Bound Bottom")
		(35 "F.Fab" user "Ref Des/Assembly Top")
		(33 "B.Fab" user "Ref Des/Assembly Bottom")
	)
	(footprint ""
		(layer "F.Cu")
		(at 436.8165 -16.129 90)
		(property "Reference" "R1U35"
			(at 0 0 90)
			(layer "F.SilkS")
			(hide yes)
			(effects
				(font
					(size 1.27 1.27)
				)
			)
		)
		(property "Value" ""
			(at 0 0 90)
			(layer "F.Fab")
			(effects
				(font
					(size 1.27 1.27)
				)
			)
		)
		(duplicate_pad_numbers_are_jumpers no)
		(fp_poly
			(pts
				(xy -0.2794 -0.1016) (xy 0.2794 -0.1016) (xy 0.2794 0.9906) (xy -0.2794 0.9906)
			)
			(stroke
				(width 0)
				(type default)
			)
			(fill no)
			(layer "F.CrtYd")
		)
		(fp_line
			(start 0.2794 -0.1016)
			(end -0.2794 -0.1016)
			(stroke
				(width 0.1)
				(type default)
			)
			(layer "F.Fab")
		)
		(fp_line
			(start -0.2794 -0.1016)
			(end -0.2794 0.9906)
			(stroke
				(width 0.1)
				(type default)
			)
			(layer "F.Fab")
		)
		(fp_line
			(start 0.2794 0.9906)
			(end 0.2794 -0.1016)
			(stroke
				(width 0.1)
				(type default)
			)
			(layer "F.Fab")
		)
		(fp_line
			(start -0.2794 0.9906)
			(end 0.2794 0.9906)
			(stroke
				(width 0.1)
				(type default)
			)
			(layer "F.Fab")
		)
		(pad "1" smd rect
			(at 0 0 90)
			(size 0.508 0.508)
			(layers "F.Cu" "F.Mask" "F.Paste")
			(net "PVCCIO_CPU1")
		)
		(pad "2" smd rect
			(at 0 0.889 90)
			(size 0.508 0.508)
			(layers "F.Cu" "F.Mask" "F.Paste")
			(net "H_CPU1_MEMKLM_MEMHOT_G_N")
		)
		(zone
			(layer "F.Cu")
			(hatch none 0.5)
			(connect_pads
				(clearance 0)
			)
			(min_thickness 0.25)
			(keepout
				(tracks allowed)
				(vias not_allowed)
				(pads allowed)
				(copperpour not_allowed)
				(footprints allowed)
			)
			(placement
				(enabled no)
				(sheetname "")
			)
			(fill
				(thermal_gap 0.5)
				(thermal_bridge_width 0.5)
				(island_removal_mode 0)
			)
			(polygon
				(pts
					(xy 437.0705 -15.875) (xy 437.0705 -16.383) (xy 437.4515 -16.383) (xy 437.4515 -15.875)
				)
			)
		)
		(zone
			(layer "F.Cu")
			(hatch none 0.5)
			(connect_pads
				(clearance 0)
			)
			(min_thickness 0.25)
			(keepout
				(tracks not_allowed)
				(vias allowed)
				(pads allowed)
				(copperpour not_allowed)
				(footprints allowed)
			)
			(placement
				(enabled no)
				(sheetname "")
			)
			(fill
				(thermal_gap 0.5)
				(thermal_bridge_width 0.5)
				(island_removal_mode 0)
			)
			(polygon
				(pts
					(xy 437.4515 -15.875) (xy 437.4515 -16.383) (xy 437.0705 -16.383) (xy 437.0705 -15.875)
				)
			)
		)
	)
	(footprint ""
		(layer "F.Cu")
		(at 258.0386 -3.321812 -90)
		(property "Reference" "C5G19"
			(at 0 0 270)
			(layer "F.SilkS")
			(hide yes)
			(effects
				(font
					(size 1.27 1.27)
				)
			)
		)
		(property "Value" ""
			(at 0 0 270)
			(layer "F.Fab")
			(effects
				(font
					(size 1.27 1.27)
				)
			)
		)
		(duplicate_pad_numbers_are_jumpers no)
		(fp_rect
			(start -0.500126 1.598422)
			(end 0.500126 -0.201422)
			(stroke
				(width 0)
				(type default)
			)
			(fill no)
			(layer "F.CrtYd")
		)
		(fp_line
			(start -0.500126 1.598422)
			(end -0.500126 -0.201422)
			(stroke
				(width 0.1)
				(type default)
			)
			(layer "F.Fab")
		)
		(fp_line
			(start 0.500126 1.598422)
			(end -0.500126 1.598422)
			(stroke
				(width 0.1)
				(type default)
			)
			(layer "F.Fab")
		)
		(fp_line
			(start -0.500126 -0.201422)
			(end 0.500126 -0.201422)
			(stroke
				(width 0.1)
				(type default)
			)
			(layer "F.Fab")
		)
		(fp_line
			(start 0.500126 -0.201422)
			(end 0.500126 1.598422)
			(stroke
				(width 0.1)
				(type default)
			)
			(layer "F.Fab")
		)
		(pad "1" smd rect
			(at 0 0 180)
			(size 0.889 0.9906)
			(layers "F.Cu" "F.Mask" "F.Paste")
			(net "PVDDQ_ABC")
		)
		(pad "2" smd rect
			(at 0 1.397 180)
			(size 0.889 0.9906)
			(layers "F.Cu" "F.Mask" "F.Paste")
			(net "GND")
		)
		(zone
			(layer "F.Cu")
			(hatch none 0.5)
			(connect_pads
				(clearance 0)
			)
			(min_thickness 0.25)
			(keepout
				(tracks not_allowed)
				(vias allowed)
				(pads allowed)
				(copperpour not_allowed)
				(footprints allowed)
			)
			(placement
				(enabled no)
				(sheetname "")
			)
			(fill
				(thermal_gap 0.5)
				(thermal_bridge_width 0.5)
				(island_removal_mode 0)
			)
			(polygon
				(pts
					(xy 257.0861 -3.817112) (xy 257.0861 -2.826512) (xy 257.5941 -2.826512) (xy 257.5941 -3.817112)
				)
			)
		)
		(zone
			(layer "F.Cu")
			(hatch none 0.5)
			(connect_pads
				(clearance 0)
			)
			(min_thickness 0.25)
			(keepout
				(tracks allowed)
				(vias not_allowed)
				(pads allowed)
				(copperpour not_allowed)
				(footprints allowed)
			)
			(placement
				(enabled no)
				(sheetname "")
			)
			(fill
				(thermal_gap 0.5)
				(thermal_bridge_width 0.5)
				(island_removal_mode 0)
			)
			(polygon
				(pts
					(xy 257.0861 -3.817112) (xy 257.0861 -2.826512) (xy 257.5941 -2.826512) (xy 257.5941 -3.817112)
				)
			)
		)
	)
	(footprint ""
		(layer "F.Cu")
		(at 434.6702 -17.5006)
		(property "Reference" "R1U61"
			(at 0 0 0)
			(layer "F.SilkS")
			(hide yes)
			(effects
				(font
					(size 1.27 1.27)
				)
			)
		)
		(property "Value" ""
			(at 0 0 0)
			(layer "F.Fab")
			(effects
				(font
					(size 1.27 1.27)
				)
			)
		)
		(duplicate_pad_numbers_are_jumpers no)
		(fp_poly
			(pts
				(xy -0.2794 -0.1016) (xy 0.2794 -0.1016) (xy 0.2794 0.9906) (xy -0.2794 0.9906)
			)
			(stroke
				(width 0)
				(type default)
			)
			(fill no)
			(layer "F.CrtYd")
		)
		(fp_line
			(start -0.2794 -0.1016)
			(end -0.2794 0.9906)
			(stroke
				(width 0.1)
				(type default)
			)
			(layer "F.Fab")
		)
		(fp_line
			(start -0.2794 0.9906)
			(end 0.2794 0.9906)
			(stroke
				(width 0.1)
				(type default)
			)
			(layer "F.Fab")
		)
		(fp_line
			(start 0.2794 -0.1016)
			(end -0.2794 -0.1016)
			(stroke
				(width 0.1)
				(type default)
			)
			(layer "F.Fab")
		)
		(fp_line
			(start 0.2794 0.9906)
			(end 0.2794 -0.1016)
			(stroke
				(width 0.1)
				(type default)
			)
			(layer "F.Fab")
		)
		(pad "1" smd rect
			(at 0 0)
			(size 0.508 0.508)
			(layers "F.Cu" "F.Mask" "F.Paste")
			(net "H_CPU1_MEMKLM_MEMHOT_LVT3_K_N")
		)
		(pad "2" smd rect
			(at 0 0.889)
			(size 0.508 0.508)
			(layers "F.Cu" "F.Mask" "F.Paste")
			(net "H_CPU1_MEMKLM_MEMHOT_G_PCH_N")
		)
		(zone
			(layer "F.Cu")
			(hatch none 0.5)
			(connect_pads
				(clearance 0)
			)
			(min_thickness 0.25)
			(keepout
				(tracks allowed)
				(vias not_allowed)
				(pads allowed)
				(copperpour not_allowed)
				(footprints allowed)
			)
			(placement
				(enabled no)
				(sheetname "")
			)
			(fill
				(thermal_gap 0.5)
				(thermal_bridge_width 0.5)
				(island_removal_mode 0)
			)
			(polygon
				(pts
					(xy 434.4162 -17.2466) (xy 434.9242 -17.2466) (xy 434.9242 -16.8656) (xy 434.4162 -16.8656)
				)
			)
		)
		(zone
			(layer "F.Cu")
			(hatch none 0.5)
			(connect_pads
				(clearance 0)
			)
			(min_thickness 0.25)
			(keepout
				(tracks not_allowed)
				(vias allowed)
				(pads allowed)
				(copperpour not_allowed)
				(footprints allowed)
			)
			(placement
				(enabled no)
				(sheetname "")
			)
			(fill
				(thermal_gap 0.5)
				(thermal_bridge_width 0.5)
				(island_removal_mode 0)
			)
			(polygon
				(pts
					(xy 434.4162 -16.8656) (xy 434.9242 -16.8656) (xy 434.9242 -17.2466) (xy 434.4162 -17.2466)
				)
			)
		)
	)
)
